(kicad_pcb
	(version 20260206)
	(generator "pcbnew")
	(generator_version "10.0")
	(general
		(thickness 1.6)
		(legacy_teardrops no)
	)
	(paper "A4")
	(title_block
		(title "12092022_DA0F0TMDCD0_F0T_Management_Board_D_brd_V3_OCP.brd")
		(comment 1 "Grand Teton / footprints 1398-1403 of 1440")
	)
	(layers
		(0 "F.Cu" signal "TOP")
		(4 "In1.Cu" signal "GND")
		(6 "In2.Cu" signal "IN1")
		(8 "In3.Cu" signal "GND1")
		(10 "In4.Cu" signal "IN2")
		(12 "In5.Cu" signal "VCC")
		(14 "In6.Cu" signal "VCC1")
		(16 "In7.Cu" signal "IN3")
		(18 "In8.Cu" signal "GND2")
		(20 "In9.Cu" signal "IN4")
		(22 "In10.Cu" signal "GND3")
		(2 "B.Cu" signal "BOTTOM")
		(9 "F.Adhes" user "F.Adhesive")
		(11 "B.Adhes" user "B.Adhesive")
		(13 "F.Paste" user "Package Geometry/Pastemask Top")
		(15 "B.Paste" user "Package Geometry/Pastemask Bottom")
		(5 "F.SilkS" user "Ref Des/Silkscreen Top")
		(7 "B.SilkS" user "Ref Des/Silkscreen Bottom")
		(1 "F.Mask" user "Board Geometry/Soldermask Top")
		(3 "B.Mask" user "Board Geometry/Soldermask Bottom")
		(17 "Dwgs.User" user "User.Drawings")
		(19 "Cmts.User" user "User.Comments")
		(21 "Eco1.User" user "User.Eco1")
		(23 "Eco2.User" user "User.Eco2")
		(25 "Edge.Cuts" user "Board Geometry/Outline")
		(27 "Margin" user)
		(31 "F.CrtYd" user "Package Geometry/Place Bound Top")
		(29 "B.CrtYd" user "Package Geometry/Place Bound Bottom")
		(35 "F.Fab" user "Ref Des/Assembly Top")
		(33 "B.Fab" user "Ref Des/Assembly Bottom")
	)
	(footprint ""
		(layer "B.Cu")
		(at 70.832472 -47.106332 90)
		(property "Reference" "R349"
			(at 0 0 90)
			(layer "B.SilkS")
			(hide yes)
			(effects
				(font
					(size 1.27 1.27)
				)
				(justify mirror)
			)
		)
		(property "Value" ""
			(at 0 0 90)
			(layer "B.Fab")
			(effects
				(font
					(size 1.27 1.27)
				)
				(justify mirror)
			)
		)
		(duplicate_pad_numbers_are_jumpers no)
		(fp_line
			(start 0.7874 -0.4064)
			(end -0.7874 -0.4064)
			(stroke
				(width 0.1524)
				(type default)
			)
			(layer "B.SilkS")
		)
		(fp_line
			(start -0.7874 -0.4064)
			(end -0.7874 0.4064)
			(stroke
				(width 0.1524)
				(type default)
			)
			(layer "B.SilkS")
		)
		(fp_line
			(start 0.7874 0.4064)
			(end 0.7874 -0.4064)
			(stroke
				(width 0.1524)
				(type default)
			)
			(layer "B.SilkS")
		)
		(fp_line
			(start -0.7874 0.4064)
			(end 0.7874 0.4064)
			(stroke
				(width 0.1524)
				(type default)
			)
			(layer "B.SilkS")
		)
		(fp_line
			(start 0.67945 -0.305054)
			(end 0.12065 -0.305054)
			(stroke
				(width 0.1)
				(type default)
			)
			(layer "B.Fab")
		)
		(fp_line
			(start 0.12065 -0.305054)
			(end 0.12065 -0.2794)
			(stroke
				(width 0.1)
				(type default)
			)
			(layer "B.Fab")
		)
		(fp_line
			(start -0.12065 -0.3048)
			(end -0.67945 -0.3048)
			(stroke
				(width 0.1)
				(type default)
			)
			(layer "B.Fab")
		)
		(fp_line
			(start -0.67945 -0.3048)
			(end -0.67945 0.3048)
			(stroke
				(width 0.1)
				(type default)
			)
			(layer "B.Fab")
		)
		(fp_line
			(start 0.12065 -0.2794)
			(end -0.12065 -0.2794)
			(stroke
				(width 0.1)
				(type default)
			)
			(layer "B.Fab")
		)
		(fp_line
			(start -0.12065 -0.2794)
			(end -0.12065 -0.3048)
			(stroke
				(width 0.1)
				(type default)
			)
			(layer "B.Fab")
		)
		(fp_line
			(start 0.12065 0.2794)
			(end 0.12065 0.3048)
			(stroke
				(width 0.1)
				(type default)
			)
			(layer "B.Fab")
		)
		(fp_line
			(start -0.120396 0.2794)
			(end 0.12065 0.2794)
			(stroke
				(width 0.1)
				(type default)
			)
			(layer "B.Fab")
		)
		(fp_line
			(start 0.67945 0.3048)
			(end 0.67945 -0.305054)
			(stroke
				(width 0.1)
				(type default)
			)
			(layer "B.Fab")
		)
		(fp_line
			(start 0.12065 0.3048)
			(end 0.67945 0.3048)
			(stroke
				(width 0.1)
				(type default)
			)
			(layer "B.Fab")
		)
		(fp_line
			(start -0.120396 0.3048)
			(end -0.120396 0.2794)
			(stroke
				(width 0.1)
				(type default)
			)
			(layer "B.Fab")
		)
		(fp_line
			(start -0.67945 0.3048)
			(end -0.120396 0.3048)
			(stroke
				(width 0.1)
				(type default)
			)
			(layer "B.Fab")
		)
		(pad "1" smd circle
			(at 0.40005 0 270)
			(size 0 0)
			(layers "B.Cu" "B.Mask" "B.Paste")
			(net "GND")
		)
		(pad "2" smd circle
			(at -0.40005 0 270)
			(size 0 0)
			(layers "B.Cu" "B.Mask" "B.Paste")
			(net "M_BMC_DDR4_MCKE")
		)
	)
	(footprint ""
		(layer "B.Cu")
		(at 68.2752 -97.5614 180)
		(property "Reference" "R493"
			(at 0 0 0)
			(layer "B.SilkS")
			(hide yes)
			(effects
				(font
					(size 1.27 1.27)
				)
				(justify mirror)
			)
		)
		(property "Value" ""
			(at 0 0 0)
			(layer "B.Fab")
			(effects
				(font
					(size 1.27 1.27)
				)
				(justify mirror)
			)
		)
		(duplicate_pad_numbers_are_jumpers no)
		(fp_line
			(start 0.7874 0.4064)
			(end 0.7874 -0.4064)
			(stroke
				(width 0.1524)
				(type default)
			)
			(layer "B.SilkS")
		)
		(fp_line
			(start 0.7874 -0.4064)
			(end -0.7874 -0.4064)
			(stroke
				(width 0.1524)
				(type default)
			)
			(layer "B.SilkS")
		)
		(fp_line
			(start -0.7874 0.4064)
			(end 0.7874 0.4064)
			(stroke
				(width 0.1524)
				(type default)
			)
			(layer "B.SilkS")
		)
		(fp_line
			(start -0.7874 -0.4064)
			(end -0.7874 0.4064)
			(stroke
				(width 0.1524)
				(type default)
			)
			(layer "B.SilkS")
		)
		(fp_line
			(start 0.67945 0.3048)
			(end 0.67945 -0.305054)
			(stroke
				(width 0.1)
				(type default)
			)
			(layer "B.Fab")
		)
		(fp_line
			(start 0.67945 -0.305054)
			(end 0.12065 -0.305054)
			(stroke
				(width 0.1)
				(type default)
			)
			(layer "B.Fab")
		)
		(fp_line
			(start 0.12065 0.3048)
			(end 0.67945 0.3048)
			(stroke
				(width 0.1)
				(type default)
			)
			(layer "B.Fab")
		)
		(fp_line
			(start 0.12065 0.2794)
			(end 0.12065 0.3048)
			(stroke
				(width 0.1)
				(type default)
			)
			(layer "B.Fab")
		)
		(fp_line
			(start 0.12065 -0.2794)
			(end -0.12065 -0.2794)
			(stroke
				(width 0.1)
				(type default)
			)
			(layer "B.Fab")
		)
		(fp_line
			(start 0.12065 -0.305054)
			(end 0.12065 -0.2794)
			(stroke
				(width 0.1)
				(type default)
			)
			(layer "B.Fab")
		)
		(fp_line
			(start -0.120396 0.3048)
			(end -0.120396 0.2794)
			(stroke
				(width 0.1)
				(type default)
			)
			(layer "B.Fab")
		)
		(fp_line
			(start -0.120396 0.2794)
			(end 0.12065 0.2794)
			(stroke
				(width 0.1)
				(type default)
			)
			(layer "B.Fab")
		)
		(fp_line
			(start -0.12065 -0.2794)
			(end -0.12065 -0.3048)
			(stroke
				(width 0.1)
				(type default)
			)
			(layer "B.Fab")
		)
		(fp_line
			(start -0.12065 -0.3048)
			(end -0.67945 -0.3048)
			(stroke
				(width 0.1)
				(type default)
			)
			(layer "B.Fab")
		)
		(fp_line
			(start -0.67945 0.3048)
			(end -0.120396 0.3048)
			(stroke
				(width 0.1)
				(type default)
			)
			(layer "B.Fab")
		)
		(fp_line
			(start -0.67945 -0.3048)
			(end -0.67945 0.3048)
			(stroke
				(width 0.1)
				(type default)
			)
			(layer "B.Fab")
		)
		(pad "1" smd circle
			(at 0.40005 0)
			(size 0 0)
			(layers "B.Cu" "B.Mask" "B.Paste")
			(net "LPC_ESPI_SEL_N")
		)
		(pad "2" smd circle
			(at -0.40005 0)
			(size 0 0)
			(layers "B.Cu" "B.Mask" "B.Paste")
			(net "GND")
		)
	)
	(footprint ""
		(layer "B.Cu")
		(at 32.766 -89.789 180)
		(property "Reference" "C257"
			(at 0 0 0)
			(layer "B.SilkS")
			(hide yes)
			(effects
				(font
					(size 1.27 1.27)
				)
				(justify mirror)
			)
		)
		(property "Value" ""
			(at 0 0 0)
			(layer "B.Fab")
			(effects
				(font
					(size 1.27 1.27)
				)
				(justify mirror)
			)
		)
		(duplicate_pad_numbers_are_jumpers no)
		(fp_line
			(start 0.7874 0.4064)
			(end 0.7874 -0.4064)
			(stroke
				(width 0.1524)
				(type default)
			)
			(layer "B.SilkS")
		)
		(fp_line
			(start 0.7874 -0.4064)
			(end -0.7874 -0.4064)
			(stroke
				(width 0.1524)
				(type default)
			)
			(layer "B.SilkS")
		)
		(fp_line
			(start -0.7874 0.4064)
			(end 0.7874 0.4064)
			(stroke
				(width 0.1524)
				(type default)
			)
			(layer "B.SilkS")
		)
		(fp_line
			(start -0.7874 -0.4064)
			(end -0.7874 0.4064)
			(stroke
				(width 0.1524)
				(type default)
			)
			(layer "B.SilkS")
		)
		(fp_line
			(start 0.67945 0.3048)
			(end 0.67945 -0.305054)
			(stroke
				(width 0.1)
				(type default)
			)
			(layer "B.Fab")
		)
		(fp_line
			(start 0.67945 -0.305054)
			(end 0.12065 -0.305054)
			(stroke
				(width 0.1)
				(type default)
			)
			(layer "B.Fab")
		)
		(fp_line
			(start 0.12065 0.3048)
			(end 0.67945 0.3048)
			(stroke
				(width 0.1)
				(type default)
			)
			(layer "B.Fab")
		)
		(fp_line
			(start 0.12065 0.2794)
			(end 0.12065 0.3048)
			(stroke
				(width 0.1)
				(type default)
			)
			(layer "B.Fab")
		)
		(fp_line
			(start 0.12065 -0.2794)
			(end -0.12065 -0.2794)
			(stroke
				(width 0.1)
				(type default)
			)
			(layer "B.Fab")
		)
		(fp_line
			(start 0.12065 -0.305054)
			(end 0.12065 -0.2794)
			(stroke
				(width 0.1)
				(type default)
			)
			(layer "B.Fab")
		)
		(fp_line
			(start -0.120396 0.3048)
			(end -0.120396 0.2794)
			(stroke
				(width 0.1)
				(type default)
			)
			(layer "B.Fab")
		)
		(fp_line
			(start -0.120396 0.2794)
			(end 0.12065 0.2794)
			(stroke
				(width 0.1)
				(type default)
			)
			(layer "B.Fab")
		)
		(fp_line
			(start -0.12065 -0.2794)
			(end -0.12065 -0.3048)
			(stroke
				(width 0.1)
				(type default)
			)
			(layer "B.Fab")
		)
		(fp_line
			(start -0.12065 -0.3048)
			(end -0.67945 -0.3048)
			(stroke
				(width 0.1)
				(type default)
			)
			(layer "B.Fab")
		)
		(fp_line
			(start -0.67945 0.3048)
			(end -0.120396 0.3048)
			(stroke
				(width 0.1)
				(type default)
			)
			(layer "B.Fab")
		)
		(fp_line
			(start -0.67945 -0.3048)
			(end -0.67945 0.3048)
			(stroke
				(width 0.1)
				(type default)
			)
			(layer "B.Fab")
		)
		(pad "1" smd circle
			(at 0.40005 0)
			(size 0 0)
			(layers "B.Cu" "B.Mask" "B.Paste")
			(net "PVCCIO_AUX_PLD")
		)
		(pad "2" smd circle
			(at -0.40005 0)
			(size 0 0)
			(layers "B.Cu" "B.Mask" "B.Paste")
			(net "GND")
		)
	)
	(footprint ""
		(layer "B.Cu")
		(at 45.419264 -34.637726 90)
		(property "Reference" "R138"
			(at 0 0 90)
			(layer "B.SilkS")
			(hide yes)
			(effects
				(font
					(size 1.27 1.27)
				)
				(justify mirror)
			)
		)
		(property "Value" ""
			(at 0 0 90)
			(layer "B.Fab")
			(effects
				(font
					(size 1.27 1.27)
				)
				(justify mirror)
			)
		)
		(duplicate_pad_numbers_are_jumpers no)
		(fp_line
			(start 0.7874 -0.4064)
			(end -0.7874 -0.4064)
			(stroke
				(width 0.1524)
				(type default)
			)
			(layer "B.SilkS")
		)
		(fp_line
			(start -0.7874 -0.4064)
			(end -0.7874 0.4064)
			(stroke
				(width 0.1524)
				(type default)
			)
			(layer "B.SilkS")
		)
		(fp_line
			(start 0.7874 0.4064)
			(end 0.7874 -0.4064)
			(stroke
				(width 0.1524)
				(type default)
			)
			(layer "B.SilkS")
		)
		(fp_line
			(start -0.7874 0.4064)
			(end 0.7874 0.4064)
			(stroke
				(width 0.1524)
				(type default)
			)
			(layer "B.SilkS")
		)
		(fp_line
			(start 0.67945 -0.305054)
			(end 0.12065 -0.305054)
			(stroke
				(width 0.1)
				(type default)
			)
			(layer "B.Fab")
		)
		(fp_line
			(start 0.12065 -0.305054)
			(end 0.12065 -0.2794)
			(stroke
				(width 0.1)
				(type default)
			)
			(layer "B.Fab")
		)
		(fp_line
			(start -0.12065 -0.3048)
			(end -0.67945 -0.3048)
			(stroke
				(width 0.1)
				(type default)
			)
			(layer "B.Fab")
		)
		(fp_line
			(start -0.67945 -0.3048)
			(end -0.67945 0.3048)
			(stroke
				(width 0.1)
				(type default)
			)
			(layer "B.Fab")
		)
		(fp_line
			(start 0.12065 -0.2794)
			(end -0.12065 -0.2794)
			(stroke
				(width 0.1)
				(type default)
			)
			(layer "B.Fab")
		)
		(fp_line
			(start -0.12065 -0.2794)
			(end -0.12065 -0.3048)
			(stroke
				(width 0.1)
				(type default)
			)
			(layer "B.Fab")
		)
		(fp_line
			(start 0.12065 0.2794)
			(end 0.12065 0.3048)
			(stroke
				(width 0.1)
				(type default)
			)
			(layer "B.Fab")
		)
		(fp_line
			(start -0.120396 0.2794)
			(end 0.12065 0.2794)
			(stroke
				(width 0.1)
				(type default)
			)
			(layer "B.Fab")
		)
		(fp_line
			(start 0.67945 0.3048)
			(end 0.67945 -0.305054)
			(stroke
				(width 0.1)
				(type default)
			)
			(layer "B.Fab")
		)
		(fp_line
			(start 0.12065 0.3048)
			(end 0.67945 0.3048)
			(stroke
				(width 0.1)
				(type default)
			)
			(layer "B.Fab")
		)
		(fp_line
			(start -0.120396 0.3048)
			(end -0.120396 0.2794)
			(stroke
				(width 0.1)
				(type default)
			)
			(layer "B.Fab")
		)
		(fp_line
			(start -0.67945 0.3048)
			(end -0.120396 0.3048)
			(stroke
				(width 0.1)
				(type default)
			)
			(layer "B.Fab")
		)
		(pad "1" smd circle
			(at 0.40005 0 270)
			(size 0 0)
			(layers "B.Cu" "B.Mask" "B.Paste")
			(net "SMB_BMC_MM4_R_SCL")
		)
		(pad "2" smd circle
			(at -0.40005 0 270)
			(size 0 0)
			(layers "B.Cu" "B.Mask" "B.Paste")
			(net "SMB_BMC_MM4_SCL")
		)
	)
	(footprint ""
		(layer "B.Cu")
		(at 32.4612 -63.4238 180)
		(property "Reference" "R546"
			(at 0 0 0)
			(layer "B.SilkS")
			(hide yes)
			(effects
				(font
					(size 1.27 1.27)
				)
				(justify mirror)
			)
		)
		(property "Value" ""
			(at 0 0 0)
			(layer "B.Fab")
			(effects
				(font
					(size 1.27 1.27)
				)
				(justify mirror)
			)
		)
		(duplicate_pad_numbers_are_jumpers no)
		(fp_line
			(start 0.7874 0.4064)
			(end 0.7874 -0.4064)
			(stroke
				(width 0.1524)
				(type default)
			)
			(layer "B.SilkS")
		)
		(fp_line
			(start 0.7874 -0.4064)
			(end -0.7874 -0.4064)
			(stroke
				(width 0.1524)
				(type default)
			)
			(layer "B.SilkS")
		)
		(fp_line
			(start -0.7874 0.4064)
			(end 0.7874 0.4064)
			(stroke
				(width 0.1524)
				(type default)
			)
			(layer "B.SilkS")
		)
		(fp_line
			(start -0.7874 -0.4064)
			(end -0.7874 0.4064)
			(stroke
				(width 0.1524)
				(type default)
			)
			(layer "B.SilkS")
		)
		(fp_line
			(start 0.67945 0.3048)
			(end 0.67945 -0.305054)
			(stroke
				(width 0.1)
				(type default)
			)
			(layer "B.Fab")
		)
		(fp_line
			(start 0.67945 -0.305054)
			(end 0.12065 -0.305054)
			(stroke
				(width 0.1)
				(type default)
			)
			(layer "B.Fab")
		)
		(fp_line
			(start 0.12065 0.3048)
			(end 0.67945 0.3048)
			(stroke
				(width 0.1)
				(type default)
			)
			(layer "B.Fab")
		)
		(fp_line
			(start 0.12065 0.2794)
			(end 0.12065 0.3048)
			(stroke
				(width 0.1)
				(type default)
			)
			(layer "B.Fab")
		)
		(fp_line
			(start 0.12065 -0.2794)
			(end -0.12065 -0.2794)
			(stroke
				(width 0.1)
				(type default)
			)
			(layer "B.Fab")
		)
		(fp_line
			(start 0.12065 -0.305054)
			(end 0.12065 -0.2794)
			(stroke
				(width 0.1)
				(type default)
			)
			(layer "B.Fab")
		)
		(fp_line
			(start -0.120396 0.3048)
			(end -0.120396 0.2794)
			(stroke
				(width 0.1)
				(type default)
			)
			(layer "B.Fab")
		)
		(fp_line
			(start -0.120396 0.2794)
			(end 0.12065 0.2794)
			(stroke
				(width 0.1)
				(type default)
			)
			(layer "B.Fab")
		)
		(fp_line
			(start -0.12065 -0.2794)
			(end -0.12065 -0.3048)
			(stroke
				(width 0.1)
				(type default)
			)
			(layer "B.Fab")
		)
		(fp_line
			(start -0.12065 -0.3048)
			(end -0.67945 -0.3048)
			(stroke
				(width 0.1)
				(type default)
			)
			(layer "B.Fab")
		)
		(fp_line
			(start -0.67945 0.3048)
			(end -0.120396 0.3048)
			(stroke
				(width 0.1)
				(type default)
			)
			(layer "B.Fab")
		)
		(fp_line
			(start -0.67945 -0.3048)
			(end -0.67945 0.3048)
			(stroke
				(width 0.1)
				(type default)
			)
			(layer "B.Fab")
		)
		(pad "1" smd circle
			(at 0.40005 0)
			(size 0 0)
			(layers "B.Cu" "B.Mask" "B.Paste")
			(net "SPA_SOUT_SW_DBG")
		)
		(pad "2" smd circle
			(at -0.40005 0)
			(size 0 0)
			(layers "B.Cu" "B.Mask" "B.Paste")
			(net "SPA_SOUT_SW_DBG_R")
		)
	)
	(footprint ""
		(layer "B.Cu")
		(at 39.37508 -44.63288)
		(property "Reference" "R422"
			(at 0 0 0)
			(layer "B.SilkS")
			(hide yes)
			(effects
				(font
					(size 1.27 1.27)
				)
				(justify mirror)
			)
		)
		(property "Value" ""
			(at 0 0 0)
			(layer "B.Fab")
			(effects
				(font
					(size 1.27 1.27)
				)
				(justify mirror)
			)
		)
		(duplicate_pad_numbers_are_jumpers no)
		(fp_line
			(start -0.7874 -0.4064)
			(end -0.7874 0.4064)
			(stroke
				(width 0.1524)
				(type default)
			)
			(layer "B.SilkS")
		)
		(fp_line
			(start -0.7874 0.4064)
			(end 0.7874 0.4064)
			(stroke
				(width 0.1524)
				(type default)
			)
			(layer "B.SilkS")
		)
		(fp_line
			(start 0.7874 -0.4064)
			(end -0.7874 -0.4064)
			(stroke
				(width 0.1524)
				(type default)
			)
			(layer "B.SilkS")
		)
		(fp_line
			(start 0.7874 0.4064)
			(end 0.7874 -0.4064)
			(stroke
				(width 0.1524)
				(type default)
			)
			(layer "B.SilkS")
		)
		(fp_line
			(start -0.67945 -0.3048)
			(end -0.67945 0.3048)
			(stroke
				(width 0.1)
				(type default)
			)
			(layer "B.Fab")
		)
		(fp_line
			(start -0.67945 0.3048)
			(end -0.120396 0.3048)
			(stroke
				(width 0.1)
				(type default)
			)
			(layer "B.Fab")
		)
		(fp_line
			(start -0.12065 -0.3048)
			(end -0.67945 -0.3048)
			(stroke
				(width 0.1)
				(type default)
			)
			(layer "B.Fab")
		)
		(fp_line
			(start -0.12065 -0.2794)
			(end -0.12065 -0.3048)
			(stroke
				(width 0.1)
				(type default)
			)
			(layer "B.Fab")
		)
		(fp_line
			(start -0.120396 0.2794)
			(end 0.12065 0.2794)
			(stroke
				(width 0.1)
				(type default)
			)
			(layer "B.Fab")
		)
		(fp_line
			(start -0.120396 0.3048)
			(end -0.120396 0.2794)
			(stroke
				(width 0.1)
				(type default)
			)
			(layer "B.Fab")
		)
		(fp_line
			(start 0.12065 -0.305054)
			(end 0.12065 -0.2794)
			(stroke
				(width 0.1)
				(type default)
			)
			(layer "B.Fab")
		)
		(fp_line
			(start 0.12065 -0.2794)
			(end -0.12065 -0.2794)
			(stroke
				(width 0.1)
				(type default)
			)
			(layer "B.Fab")
		)
		(fp_line
			(start 0.12065 0.2794)
			(end 0.12065 0.3048)
			(stroke
				(width 0.1)
				(type default)
			)
			(layer "B.Fab")
		)
		(fp_line
			(start 0.12065 0.3048)
			(end 0.67945 0.3048)
			(stroke
				(width 0.1)
				(type default)
			)
			(layer "B.Fab")
		)
		(fp_line
			(start 0.67945 -0.305054)
			(end 0.12065 -0.305054)
			(stroke
				(width 0.1)
				(type default)
			)
			(layer "B.Fab")
		)
		(fp_line
			(start 0.67945 0.3048)
			(end 0.67945 -0.305054)
			(stroke
				(width 0.1)
				(type default)
			)
			(layer "B.Fab")
		)
		(pad "1" smd circle
			(at 0.40005 0 180)
			(size 0 0)
			(layers "B.Cu" "B.Mask" "B.Paste")
			(net "P3V3_AUX")
		)
		(pad "2" smd circle
			(at -0.40005 0 180)
			(size 0 0)
			(layers "B.Cu" "B.Mask" "B.Paste")
			(net "SMB_BMC_MM13_SCL")
		)
	)
)
